(kicad_pcb
	(version 20260206)
	(generator "pcbnew")
	(generator_version "10.0")
	(general
		(thickness 1.6)
		(legacy_teardrops no)
	)
	(paper "A4")
	(title_block
		(title "01162023_DA0F0TEBIF0_F0T_Expander_BD_F_brd_V02_OCP.brd")
		(comment 1 "Grand Teton / footprints 5050-5057 of 9728")
	)
	(layers
		(0 "F.Cu" signal "TOP")
		(4 "In1.Cu" signal "GND")
		(6 "In2.Cu" signal "VCC")
		(8 "In3.Cu" signal "VCC1")
		(10 "In4.Cu" signal "GND1")
		(12 "In5.Cu" signal "IN1")
		(14 "In6.Cu" signal "GND2")
		(16 "In7.Cu" signal "IN2")
		(18 "In8.Cu" signal "GND3")
		(20 "In9.Cu" signal "IN3")
		(22 "In10.Cu" signal "GND4")
		(24 "In11.Cu" signal "IN4")
		(26 "In12.Cu" signal "GND5")
		(28 "In13.Cu" signal "IN5")
		(30 "In14.Cu" signal "GND6")
		(32 "In15.Cu" signal "IN6")
		(34 "In16.Cu" signal "GND7")
		(2 "B.Cu" signal "BOTTOM")
		(9 "F.Adhes" user "F.Adhesive")
		(11 "B.Adhes" user "B.Adhesive")
		(13 "F.Paste" user "Package Geometry/Pastemask Top")
		(15 "B.Paste" user "Package Geometry/Pastemask Bottom")
		(5 "F.SilkS" user "Ref Des/Silkscreen Top")
		(7 "B.SilkS" user "Ref Des/Silkscreen Bottom")
		(1 "F.Mask" user "Board Geometry/Soldermask Top")
		(3 "B.Mask" user "Board Geometry/Soldermask Bottom")
		(17 "Dwgs.User" user "User.Drawings")
		(19 "Cmts.User" user "User.Comments")
		(21 "Eco1.User" user "User.Eco1")
		(23 "Eco2.User" user "User.Eco2")
		(25 "Edge.Cuts" user "Board Geometry/Outline")
		(27 "Margin" user)
		(31 "F.CrtYd" user "Package Geometry/Place Bound Top")
		(29 "B.CrtYd" user "Package Geometry/Place Bound Bottom")
		(35 "F.Fab" user "Ref Des/Assembly Top")
		(33 "B.Fab" user "Ref Des/Assembly Bottom")
	)
	(footprint ""
		(layer "F.Cu")
		(at 430.826672 -53.697124 -90)
		(property "Reference" "PC582"
			(at 0 0 270)
			(layer "F.SilkS")
			(hide yes)
			(effects
				(font
					(size 1.27 1.27)
				)
			)
		)
		(property "Value" ""
			(at 0 0 270)
			(layer "F.Fab")
			(effects
				(font
					(size 1.27 1.27)
				)
			)
		)
		(duplicate_pad_numbers_are_jumpers no)
		(fp_line
			(start -0.7874 0.4064)
			(end -0.7874 -0.4064)
			(stroke
				(width 0.1524)
				(type default)
			)
			(layer "F.SilkS")
		)
		(fp_line
			(start 0.7874 0.4064)
			(end -0.7874 0.4064)
			(stroke
				(width 0.1524)
				(type default)
			)
			(layer "F.SilkS")
		)
		(fp_line
			(start -0.7874 -0.4064)
			(end 0.7874 -0.4064)
			(stroke
				(width 0.1524)
				(type default)
			)
			(layer "F.SilkS")
		)
		(fp_line
			(start 0.7874 -0.4064)
			(end 0.7874 0.4064)
			(stroke
				(width 0.1524)
				(type default)
			)
			(layer "F.SilkS")
		)
		(fp_line
			(start -0.67945 0.3048)
			(end -0.67945 -0.305054)
			(stroke
				(width 0.1)
				(type default)
			)
			(layer "F.Fab")
		)
		(fp_line
			(start -0.12065 0.3048)
			(end -0.67945 0.3048)
			(stroke
				(width 0.1)
				(type default)
			)
			(layer "F.Fab")
		)
		(fp_line
			(start 0.120396 0.3048)
			(end 0.120396 0.2794)
			(stroke
				(width 0.1)
				(type default)
			)
			(layer "F.Fab")
		)
		(fp_line
			(start 0.67945 0.3048)
			(end 0.120396 0.3048)
			(stroke
				(width 0.1)
				(type default)
			)
			(layer "F.Fab")
		)
		(fp_line
			(start -0.12065 0.2794)
			(end -0.12065 0.3048)
			(stroke
				(width 0.1)
				(type default)
			)
			(layer "F.Fab")
		)
		(fp_line
			(start 0.120396 0.2794)
			(end -0.12065 0.2794)
			(stroke
				(width 0.1)
				(type default)
			)
			(layer "F.Fab")
		)
		(fp_line
			(start -0.12065 -0.2794)
			(end 0.12065 -0.2794)
			(stroke
				(width 0.1)
				(type default)
			)
			(layer "F.Fab")
		)
		(fp_line
			(start 0.12065 -0.2794)
			(end 0.12065 -0.3048)
			(stroke
				(width 0.1)
				(type default)
			)
			(layer "F.Fab")
		)
		(fp_line
			(start 0.12065 -0.3048)
			(end 0.67945 -0.3048)
			(stroke
				(width 0.1)
				(type default)
			)
			(layer "F.Fab")
		)
		(fp_line
			(start 0.67945 -0.3048)
			(end 0.67945 0.3048)
			(stroke
				(width 0.1)
				(type default)
			)
			(layer "F.Fab")
		)
		(fp_line
			(start -0.67945 -0.305054)
			(end -0.12065 -0.305054)
			(stroke
				(width 0.1)
				(type default)
			)
			(layer "F.Fab")
		)
		(fp_line
			(start -0.12065 -0.305054)
			(end -0.12065 -0.2794)
			(stroke
				(width 0.1)
				(type default)
			)
			(layer "F.Fab")
		)
		(pad "1" smd circle
			(at -0.40005 0 270)
			(size 0 0)
			(layers "F.Cu" "F.Mask" "F.Paste")
			(net "P3V3_AUX")
		)
		(pad "2" smd circle
			(at 0.40005 0 270)
			(size 0 0)
			(layers "F.Cu" "F.Mask" "F.Paste")
			(net "GND")
		)
	)
	(footprint ""
		(layer "F.Cu")
		(at 102.428802 -293.816786 -90)
		(property "Reference" "PC83"
			(at 0 0 270)
			(layer "F.SilkS")
			(hide yes)
			(effects
				(font
					(size 1.27 1.27)
				)
			)
		)
		(property "Value" ""
			(at 0 0 270)
			(layer "F.Fab")
			(effects
				(font
					(size 1.27 1.27)
				)
			)
		)
		(duplicate_pad_numbers_are_jumpers no)
		(fp_line
			(start -0.7874 0.4064)
			(end -0.7874 -0.4064)
			(stroke
				(width 0.1524)
				(type default)
			)
			(layer "F.SilkS")
		)
		(fp_line
			(start 0.7874 0.4064)
			(end -0.7874 0.4064)
			(stroke
				(width 0.1524)
				(type default)
			)
			(layer "F.SilkS")
		)
		(fp_line
			(start -0.7874 -0.4064)
			(end 0.7874 -0.4064)
			(stroke
				(width 0.1524)
				(type default)
			)
			(layer "F.SilkS")
		)
		(fp_line
			(start 0.7874 -0.4064)
			(end 0.7874 0.4064)
			(stroke
				(width 0.1524)
				(type default)
			)
			(layer "F.SilkS")
		)
		(fp_line
			(start -0.67945 0.3048)
			(end -0.67945 -0.305054)
			(stroke
				(width 0.1)
				(type default)
			)
			(layer "F.Fab")
		)
		(fp_line
			(start -0.12065 0.3048)
			(end -0.67945 0.3048)
			(stroke
				(width 0.1)
				(type default)
			)
			(layer "F.Fab")
		)
		(fp_line
			(start 0.120396 0.3048)
			(end 0.120396 0.2794)
			(stroke
				(width 0.1)
				(type default)
			)
			(layer "F.Fab")
		)
		(fp_line
			(start 0.67945 0.3048)
			(end 0.120396 0.3048)
			(stroke
				(width 0.1)
				(type default)
			)
			(layer "F.Fab")
		)
		(fp_line
			(start -0.12065 0.2794)
			(end -0.12065 0.3048)
			(stroke
				(width 0.1)
				(type default)
			)
			(layer "F.Fab")
		)
		(fp_line
			(start 0.120396 0.2794)
			(end -0.12065 0.2794)
			(stroke
				(width 0.1)
				(type default)
			)
			(layer "F.Fab")
		)
		(fp_line
			(start -0.12065 -0.2794)
			(end 0.12065 -0.2794)
			(stroke
				(width 0.1)
				(type default)
			)
			(layer "F.Fab")
		)
		(fp_line
			(start 0.12065 -0.2794)
			(end 0.12065 -0.3048)
			(stroke
				(width 0.1)
				(type default)
			)
			(layer "F.Fab")
		)
		(fp_line
			(start 0.12065 -0.3048)
			(end 0.67945 -0.3048)
			(stroke
				(width 0.1)
				(type default)
			)
			(layer "F.Fab")
		)
		(fp_line
			(start 0.67945 -0.3048)
			(end 0.67945 0.3048)
			(stroke
				(width 0.1)
				(type default)
			)
			(layer "F.Fab")
		)
		(fp_line
			(start -0.67945 -0.305054)
			(end -0.12065 -0.305054)
			(stroke
				(width 0.1)
				(type default)
			)
			(layer "F.Fab")
		)
		(fp_line
			(start -0.12065 -0.305054)
			(end -0.12065 -0.2794)
			(stroke
				(width 0.1)
				(type default)
			)
			(layer "F.Fab")
		)
		(pad "1" smd circle
			(at -0.40005 0 270)
			(size 0 0)
			(layers "F.Cu" "F.Mask" "F.Paste")
			(net "P0V8_PEX0")
		)
		(pad "2" smd circle
			(at 0.40005 0 270)
			(size 0 0)
			(layers "F.Cu" "F.Mask" "F.Paste")
			(net "GND")
		)
	)
	(footprint ""
		(layer "F.Cu")
		(at 138.985244 -96.957642 180)
		(property "Reference" "R1559"
			(at 0 0 180)
			(layer "F.SilkS")
			(hide yes)
			(effects
				(font
					(size 1.27 1.27)
				)
			)
		)
		(property "Value" ""
			(at 0 0 180)
			(layer "F.Fab")
			(effects
				(font
					(size 1.27 1.27)
				)
			)
		)
		(duplicate_pad_numbers_are_jumpers no)
		(fp_line
			(start 0.7874 0.4064)
			(end -0.7874 0.4064)
			(stroke
				(width 0.1524)
				(type default)
			)
			(layer "F.SilkS")
		)
		(fp_line
			(start 0.7874 -0.4064)
			(end 0.7874 0.4064)
			(stroke
				(width 0.1524)
				(type default)
			)
			(layer "F.SilkS")
		)
		(fp_line
			(start -0.7874 0.4064)
			(end -0.7874 -0.4064)
			(stroke
				(width 0.1524)
				(type default)
			)
			(layer "F.SilkS")
		)
		(fp_line
			(start -0.7874 -0.4064)
			(end 0.7874 -0.4064)
			(stroke
				(width 0.1524)
				(type default)
			)
			(layer "F.SilkS")
		)
		(fp_line
			(start 0.67945 0.3048)
			(end 0.120396 0.3048)
			(stroke
				(width 0.1)
				(type default)
			)
			(layer "F.Fab")
		)
		(fp_line
			(start 0.67945 -0.3048)
			(end 0.67945 0.3048)
			(stroke
				(width 0.1)
				(type default)
			)
			(layer "F.Fab")
		)
		(fp_line
			(start 0.12065 -0.2794)
			(end 0.12065 -0.3048)
			(stroke
				(width 0.1)
				(type default)
			)
			(layer "F.Fab")
		)
		(fp_line
			(start 0.12065 -0.3048)
			(end 0.67945 -0.3048)
			(stroke
				(width 0.1)
				(type default)
			)
			(layer "F.Fab")
		)
		(fp_line
			(start 0.120396 0.3048)
			(end 0.120396 0.2794)
			(stroke
				(width 0.1)
				(type default)
			)
			(layer "F.Fab")
		)
		(fp_line
			(start 0.120396 0.2794)
			(end -0.12065 0.2794)
			(stroke
				(width 0.1)
				(type default)
			)
			(layer "F.Fab")
		)
		(fp_line
			(start -0.12065 0.3048)
			(end -0.67945 0.3048)
			(stroke
				(width 0.1)
				(type default)
			)
			(layer "F.Fab")
		)
		(fp_line
			(start -0.12065 0.2794)
			(end -0.12065 0.3048)
			(stroke
				(width 0.1)
				(type default)
			)
			(layer "F.Fab")
		)
		(fp_line
			(start -0.12065 -0.2794)
			(end 0.12065 -0.2794)
			(stroke
				(width 0.1)
				(type default)
			)
			(layer "F.Fab")
		)
		(fp_line
			(start -0.12065 -0.305054)
			(end -0.12065 -0.2794)
			(stroke
				(width 0.1)
				(type default)
			)
			(layer "F.Fab")
		)
		(fp_line
			(start -0.67945 0.3048)
			(end -0.67945 -0.305054)
			(stroke
				(width 0.1)
				(type default)
			)
			(layer "F.Fab")
		)
		(fp_line
			(start -0.67945 -0.305054)
			(end -0.12065 -0.305054)
			(stroke
				(width 0.1)
				(type default)
			)
			(layer "F.Fab")
		)
		(pad "1" smd circle
			(at -0.40005 0 180)
			(size 0 0)
			(layers "F.Cu" "F.Mask" "F.Paste")
			(net "P3V3_AUX")
		)
		(pad "2" smd circle
			(at 0.40005 0 180)
			(size 0 0)
			(layers "F.Cu" "F.Mask" "F.Paste")
			(net "BIC_I2C9_SSD_MUX0_A2")
		)
	)
	(footprint ""
		(layer "F.Cu")
		(at 366.092486 -32.739584 180)
		(property "Reference" "C700"
			(at 0 0 180)
			(layer "F.SilkS")
			(hide yes)
			(effects
				(font
					(size 1.27 1.27)
				)
			)
		)
		(property "Value" ""
			(at 0 0 180)
			(layer "F.Fab")
			(effects
				(font
					(size 1.27 1.27)
				)
			)
		)
		(duplicate_pad_numbers_are_jumpers no)
		(fp_line
			(start 0.299974 0.150114)
			(end -0.299974 0.150114)
			(stroke
				(width 0.1)
				(type default)
			)
			(layer "F.Fab")
		)
		(fp_line
			(start 0.299974 -0.150114)
			(end 0.299974 0.150114)
			(stroke
				(width 0.1)
				(type default)
			)
			(layer "F.Fab")
		)
		(fp_line
			(start -0.299974 0.150114)
			(end -0.299974 -0.150114)
			(stroke
				(width 0.1)
				(type default)
			)
			(layer "F.Fab")
		)
		(fp_line
			(start -0.299974 -0.150114)
			(end 0.299974 -0.150114)
			(stroke
				(width 0.1)
				(type default)
			)
			(layer "F.Fab")
		)
		(pad "1" smd rect
			(at -0.2667 0 180)
			(size 0.3048 0.381)
			(layers "F.Cu" "F.Mask" "F.Paste")
			(net "P5E_PEX3_STN2_TX_DP<46>")
		)
		(pad "2" smd rect
			(at 0.2667 0 180)
			(size 0.3048 0.381)
			(layers "F.Cu" "F.Mask" "F.Paste")
			(net "P5E_PEX3_STN2_TX_C_DP<46>")
		)
	)
	(footprint ""
		(layer "F.Cu")
		(at 375.230136 -297.205908 -90)
		(property "Reference" "C3537"
			(at 0 0 270)
			(layer "F.SilkS")
			(hide yes)
			(effects
				(font
					(size 1.27 1.27)
				)
			)
		)
		(property "Value" ""
			(at 0 0 270)
			(layer "F.Fab")
			(effects
				(font
					(size 1.27 1.27)
				)
			)
		)
		(duplicate_pad_numbers_are_jumpers no)
		(fp_line
			(start -1.2954 0.5842)
			(end -1.2954 -0.5842)
			(stroke
				(width 0.1524)
				(type default)
			)
			(layer "F.SilkS")
		)
		(fp_line
			(start 1.2954 0.5842)
			(end -1.2954 0.5842)
			(stroke
				(width 0.1524)
				(type default)
			)
			(layer "F.SilkS")
		)
		(fp_line
			(start -1.2954 -0.5842)
			(end 1.2954 -0.5842)
			(stroke
				(width 0.1524)
				(type default)
			)
			(layer "F.SilkS")
		)
		(fp_line
			(start 1.2954 -0.5842)
			(end 1.2954 0.5842)
			(stroke
				(width 0.1524)
				(type default)
			)
			(layer "F.SilkS")
		)
		(fp_line
			(start -0.8636 0.4572)
			(end -0.8636 0.4064)
			(stroke
				(width 0.1)
				(type default)
			)
			(layer "F.Fab")
		)
		(fp_line
			(start 0.8636 0.4572)
			(end -0.8636 0.4572)
			(stroke
				(width 0.1)
				(type default)
			)
			(layer "F.Fab")
		)
		(fp_line
			(start -1.1938 0.4064)
			(end -1.1938 -0.4064)
			(stroke
				(width 0.1)
				(type default)
			)
			(layer "F.Fab")
		)
		(fp_line
			(start -0.8636 0.4064)
			(end -1.1938 0.4064)
			(stroke
				(width 0.1)
				(type default)
			)
			(layer "F.Fab")
		)
		(fp_line
			(start 0.8636 0.4064)
			(end 0.8636 0.4572)
			(stroke
				(width 0.1)
				(type default)
			)
			(layer "F.Fab")
		)
		(fp_line
			(start 1.1938 0.4064)
			(end 0.8636 0.4064)
			(stroke
				(width 0.1)
				(type default)
			)
			(layer "F.Fab")
		)
		(fp_line
			(start -1.1938 -0.4064)
			(end -0.8636 -0.4064)
			(stroke
				(width 0.1)
				(type default)
			)
			(layer "F.Fab")
		)
		(fp_line
			(start -0.8636 -0.4064)
			(end -0.8636 -0.4572)
			(stroke
				(width 0.1)
				(type default)
			)
			(layer "F.Fab")
		)
		(fp_line
			(start 0.8636 -0.4064)
			(end 1.1938 -0.4064)
			(stroke
				(width 0.1)
				(type default)
			)
			(layer "F.Fab")
		)
		(fp_line
			(start 1.1938 -0.4064)
			(end 1.1938 0.4064)
			(stroke
				(width 0.1)
				(type default)
			)
			(layer "F.Fab")
		)
		(fp_line
			(start -0.8636 -0.4572)
			(end 0.8636 -0.4572)
			(stroke
				(width 0.1)
				(type default)
			)
			(layer "F.Fab")
		)
		(fp_line
			(start 0.8636 -0.4572)
			(end 0.8636 -0.4064)
			(stroke
				(width 0.1)
				(type default)
			)
			(layer "F.Fab")
		)
		(pad "1" smd rect
			(at -0.7366 0 180)
			(size 0.7112 0.8128)
			(layers "F.Cu" "F.Mask" "F.Paste")
			(net "P1V8_PLL0_PEX3")
		)
		(pad "2" smd rect
			(at 0.7366 0 180)
			(size 0.7112 0.8128)
			(layers "F.Cu" "F.Mask" "F.Paste")
			(net "GND")
		)
	)
	(footprint ""
		(layer "F.Cu")
		(at 274.18792 -45.704252 90)
		(property "Reference" "R605"
			(at 0 0 90)
			(layer "F.SilkS")
			(hide yes)
			(effects
				(font
					(size 1.27 1.27)
				)
			)
		)
		(property "Value" ""
			(at 0 0 90)
			(layer "F.Fab")
			(effects
				(font
					(size 1.27 1.27)
				)
			)
		)
		(duplicate_pad_numbers_are_jumpers no)
		(fp_line
			(start 3.937508 -1.8796)
			(end -3.937508 -1.8796)
			(stroke
				(width 0.1524)
				(type default)
			)
			(layer "F.SilkS")
		)
		(fp_line
			(start -3.937508 -1.8796)
			(end -3.937508 1.8796)
			(stroke
				(width 0.1524)
				(type default)
			)
			(layer "F.SilkS")
		)
		(fp_line
			(start 3.937508 1.8796)
			(end 3.937508 -1.8796)
			(stroke
				(width 0.1524)
				(type default)
			)
			(layer "F.SilkS")
		)
		(fp_line
			(start -3.937508 1.8796)
			(end 3.937508 1.8796)
			(stroke
				(width 0.1524)
				(type default)
			)
			(layer "F.SilkS")
		)
		(fp_line
			(start 3.275076 -1.674876)
			(end -3.275076 -1.674876)
			(stroke
				(width 0.1)
				(type default)
			)
			(layer "F.Fab")
		)
		(fp_line
			(start -3.275076 -1.674876)
			(end -3.275076 1.674876)
			(stroke
				(width 0.1)
				(type default)
			)
			(layer "F.Fab")
		)
		(fp_line
			(start 3.275076 1.674876)
			(end 3.275076 -1.674876)
			(stroke
				(width 0.1)
				(type default)
			)
			(layer "F.Fab")
		)
		(fp_line
			(start -3.275076 1.674876)
			(end 3.275076 1.674876)
			(stroke
				(width 0.1)
				(type default)
			)
			(layer "F.Fab")
		)
		(pad "1" smd rect
			(at -2.350008 0 90)
			(size 2.921 3.5052)
			(layers "F.Cu" "F.Mask" "F.Paste")
			(net "P12V_SSD9")
		)
		(pad "2" smd rect
			(at 2.350008 0 90)
			(size 2.921 3.5052)
			(layers "F.Cu" "F.Mask" "F.Paste")
			(net "P12V_SSD9_R")
		)
	)
	(footprint ""
		(layer "F.Cu")
		(at 229.88778 -308.095396 -90)
		(property "Reference" "PC979"
			(at 0 0 270)
			(layer "F.SilkS")
			(hide yes)
			(effects
				(font
					(size 1.27 1.27)
				)
			)
		)
		(property "Value" ""
			(at 0 0 270)
			(layer "F.Fab")
			(effects
				(font
					(size 1.27 1.27)
				)
			)
		)
		(duplicate_pad_numbers_are_jumpers no)
		(fp_line
			(start -0.7874 0.4064)
			(end -0.7874 -0.4064)
			(stroke
				(width 0.1524)
				(type default)
			)
			(layer "F.SilkS")
		)
		(fp_line
			(start 0.7874 0.4064)
			(end -0.7874 0.4064)
			(stroke
				(width 0.1524)
				(type default)
			)
			(layer "F.SilkS")
		)
		(fp_line
			(start -0.7874 -0.4064)
			(end 0.7874 -0.4064)
			(stroke
				(width 0.1524)
				(type default)
			)
			(layer "F.SilkS")
		)
		(fp_line
			(start 0.7874 -0.4064)
			(end 0.7874 0.4064)
			(stroke
				(width 0.1524)
				(type default)
			)
			(layer "F.SilkS")
		)
		(fp_line
			(start -0.67945 0.3048)
			(end -0.67945 -0.305054)
			(stroke
				(width 0.1)
				(type default)
			)
			(layer "F.Fab")
		)
		(fp_line
			(start -0.12065 0.3048)
			(end -0.67945 0.3048)
			(stroke
				(width 0.1)
				(type default)
			)
			(layer "F.Fab")
		)
		(fp_line
			(start 0.120396 0.3048)
			(end 0.120396 0.2794)
			(stroke
				(width 0.1)
				(type default)
			)
			(layer "F.Fab")
		)
		(fp_line
			(start 0.67945 0.3048)
			(end 0.120396 0.3048)
			(stroke
				(width 0.1)
				(type default)
			)
			(layer "F.Fab")
		)
		(fp_line
			(start -0.12065 0.2794)
			(end -0.12065 0.3048)
			(stroke
				(width 0.1)
				(type default)
			)
			(layer "F.Fab")
		)
		(fp_line
			(start 0.120396 0.2794)
			(end -0.12065 0.2794)
			(stroke
				(width 0.1)
				(type default)
			)
			(layer "F.Fab")
		)
		(fp_line
			(start -0.12065 -0.2794)
			(end 0.12065 -0.2794)
			(stroke
				(width 0.1)
				(type default)
			)
			(layer "F.Fab")
		)
		(fp_line
			(start 0.12065 -0.2794)
			(end 0.12065 -0.3048)
			(stroke
				(width 0.1)
				(type default)
			)
			(layer "F.Fab")
		)
		(fp_line
			(start 0.12065 -0.3048)
			(end 0.67945 -0.3048)
			(stroke
				(width 0.1)
				(type default)
			)
			(layer "F.Fab")
		)
		(fp_line
			(start 0.67945 -0.3048)
			(end 0.67945 0.3048)
			(stroke
				(width 0.1)
				(type default)
			)
			(layer "F.Fab")
		)
		(fp_line
			(start -0.67945 -0.305054)
			(end -0.12065 -0.305054)
			(stroke
				(width 0.1)
				(type default)
			)
			(layer "F.Fab")
		)
		(fp_line
			(start -0.12065 -0.305054)
			(end -0.12065 -0.2794)
			(stroke
				(width 0.1)
				(type default)
			)
			(layer "F.Fab")
		)
		(pad "1" smd circle
			(at -0.40005 0 270)
			(size 0 0)
			(layers "F.Cu" "F.Mask" "F.Paste")
			(net "SH_P1V25_PEX1_FB_P")
		)
		(pad "2" smd circle
			(at 0.40005 0 270)
			(size 0 0)
			(layers "F.Cu" "F.Mask" "F.Paste")
			(net "SH_P1V25_PEX1_FB_N")
		)
	)
	(footprint ""
		(layer "F.Cu")
		(at 271.480534 -132.215382)
		(property "Reference" "C459"
			(at 0 0 0)
			(layer "F.SilkS")
			(hide yes)
			(effects
				(font
					(size 1.27 1.27)
				)
			)
		)
		(property "Value" ""
			(at 0 0 0)
			(layer "F.Fab")
			(effects
				(font
					(size 1.27 1.27)
				)
			)
		)
		(duplicate_pad_numbers_are_jumpers no)
		(fp_line
			(start -0.299974 -0.150114)
			(end 0.299974 -0.150114)
			(stroke
				(width 0.1)
				(type default)
			)
			(layer "F.Fab")
		)
		(fp_line
			(start -0.299974 0.150114)
			(end -0.299974 -0.150114)
			(stroke
				(width 0.1)
				(type default)
			)
			(layer "F.Fab")
		)
		(fp_line
			(start 0.299974 -0.150114)
			(end 0.299974 0.150114)
			(stroke
				(width 0.1)
				(type default)
			)
			(layer "F.Fab")
		)
		(fp_line
			(start 0.299974 0.150114)
			(end -0.299974 0.150114)
			(stroke
				(width 0.1)
				(type default)
			)
			(layer "F.Fab")
		)
		(pad "1" smd rect
			(at -0.2667 0)
			(size 0.3048 0.381)
			(layers "F.Cu" "F.Mask" "F.Paste")
			(net "P5E_PEX2_STN1_TX_DN<29>")
		)
		(pad "2" smd rect
			(at 0.2667 0)
			(size 0.3048 0.381)
			(layers "F.Cu" "F.Mask" "F.Paste")
			(net "P5E_PEX2_STN1_TX_C_DN<29>")
		)
	)
)
